(kicad_pcb
	(version 20221018)
	(generator pcbnew)
	(general
    (thickness 1.518)
  )
	(paper "A4")
	(title_block
    (title "Kria K26 Devboard")
    (date "2024-03-26")
    (rev "1.2.5")
    (comment 1 "www.antmicro.com")
    (comment 2 "Antmicro Ltd.")
		(comment 9 "footprints 369-378 of 660")
	)
	(layers
    (0 "F.Cu" mixed)
    (1 "In1.Cu" power)
    (2 "In2.Cu" mixed)
    (3 "In3.Cu" power)
    (4 "In4.Cu" mixed)
    (5 "In5.Cu" power)
    (6 "In6.Cu" mixed)
    (31 "B.Cu" power)
    (32 "B.Adhes" user "B.Adhesive")
    (33 "F.Adhes" user "F.Adhesive")
    (34 "B.Paste" user)
    (35 "F.Paste" user)
    (36 "B.SilkS" user "B.Silkscreen")
    (37 "F.SilkS" user "F.Silkscreen")
    (38 "B.Mask" user)
    (39 "F.Mask" user)
    (40 "Dwgs.User" user "User.Drawings")
    (41 "Cmts.User" user "User.Comments")
    (42 "Eco1.User" user "User.Eco1")
    (43 "Eco2.User" user "User.Eco2")
    (44 "Edge.Cuts" user)
    (45 "Margin" user)
    (46 "B.CrtYd" user "B.Courtyard")
    (47 "F.CrtYd" user "F.Courtyard")
    (48 "B.Fab" user)
    (49 "F.Fab" user)
  )
	(footprint "kria-k26-devboard-footprints:R_0402_1005Metric" (layer "F.Cu")
    (at 114.3 89.875)
    (descr "Resistor SMD 0402")
    (tags "resistor SMD 0402")
    (property "Author" "Antmicro")
    (property "DNP" "DNP")
    (property "License" "Apache-2.0")
    (property "MPN" "CR0402-FX-4701GLF")
    (property "Manufacturer" "Bourns")
    (property "Sheetfile" "usb.kicad_sch")
    (property "Sheetname" "USB")
    (property "Tolerance" "1%")
    (property "Val" "4k7")
    (property "dnp" "")
    (property "exclude_from_bom" "")
    (property "ki_description" "4k7 resistor in 0402 package with 1% tolerance")
    (attr exclude_from_pos_files exclude_from_bom)
    (fp_text reference "R63" (at -3.156942 0.655139) (layer "F.SilkS")
        (effects (font (size 0.7 0.7) (thickness 0.15)) (justify left bottom))
    )
    (fp_text value "R_4k7_0402" (at 0 1.4) (layer "F.Fab") hide
        (effects (font (size 0.7 0.7) (thickness 0.15)) (justify left bottom))
    )
    (fp_text user "${REFERENCE}" (at -0.95 3.168) (layer "F.Fab") hide
        (effects (font (size 0.7 0.7) (thickness 0.15)) (justify left bottom))
    )
    (fp_text user "Author: Antmicro" (at -0.95 4.169) (layer "F.Fab") hide
        (effects (font (size 0.7 0.7) (thickness 0.15)) (justify left bottom))
    )
    (fp_text user "License: Apache-2.0" (at -0.95 5.169) (layer "F.Fab") hide
        (effects (font (size 0.7 0.7) (thickness 0.15)) (justify left bottom))
    )
    (fp_rect (start -0.93 -0.47) (end 0.93 0.47)
      (stroke (width 0.05) (type solid)) (fill none) (layer "F.CrtYd"))
    (fp_rect (start -0.5 -0.25) (end 0.5 0.25)
      (stroke (width 0.15) (type solid)) (fill none) (layer "F.Fab"))
    (pad "1" smd roundrect (at -0.485 0) (size 0.59 0.64) (layers "F.Cu" "F.Paste" "F.Mask") (roundrect_rratio 0.25)
      (net 15 "PS_3V3") (pintype "passive"))
    (pad "2" smd roundrect (at 0.485 0) (size 0.59 0.64) (layers "F.Cu" "F.Paste" "F.Mask") (roundrect_rratio 0.25)
      (net 666 "Net-(U17-PF26)") (pintype "passive"))
  )
	(footprint "kria-k26-devboard-footprints:R_0402_1005Metric" (layer "F.Cu")
    (at 116.45 92.55 90)
    (descr "Resistor SMD 0402")
    (tags "resistor SMD 0402")
    (property "Author" "Antmicro")
    (property "DNP" "DNP")
    (property "License" "Apache-2.0")
    (property "MPN" "CR0402-FX-4701GLF")
    (property "Manufacturer" "Bourns")
    (property "Sheetfile" "usb.kicad_sch")
    (property "Sheetname" "USB")
    (property "Tolerance" "1%")
    (property "Val" "4k7")
    (property "dnp" "")
    (property "exclude_from_bom" "")
    (property "ki_description" "4k7 resistor in 0402 package with 1% tolerance")
    (attr exclude_from_pos_files exclude_from_bom)
    (fp_text reference "R64" (at -1 -0.58 90) (layer "F.SilkS")
        (effects (font (size 0.7 0.7) (thickness 0.15)) (justify left bottom))
    )
    (fp_text value "R_4k7_0402" (at 0 1.4 90) (layer "F.Fab") hide
        (effects (font (size 0.7 0.7) (thickness 0.15)) (justify left bottom))
    )
    (fp_text user "Author: Antmicro" (at -0.95 4.169 90) (layer "F.Fab") hide
        (effects (font (size 0.7 0.7) (thickness 0.15)) (justify left bottom))
    )
    (fp_text user "${REFERENCE}" (at -0.95 3.168 90) (layer "F.Fab") hide
        (effects (font (size 0.7 0.7) (thickness 0.15)) (justify left bottom))
    )
    (fp_text user "License: Apache-2.0" (at -0.95 5.169 90) (layer "F.Fab") hide
        (effects (font (size 0.7 0.7) (thickness 0.15)) (justify left bottom))
    )
    (fp_rect (start -0.93 -0.47) (end 0.93 0.47)
      (stroke (width 0.05) (type solid)) (fill none) (layer "F.CrtYd"))
    (fp_rect (start -0.5 -0.25) (end 0.5 0.25)
      (stroke (width 0.15) (type solid)) (fill none) (layer "F.Fab"))
    (pad "1" smd roundrect (at -0.485 0 90) (size 0.59 0.64) (layers "F.Cu" "F.Paste" "F.Mask") (roundrect_rratio 0.25)
      (net 15 "PS_3V3") (pintype "passive"))
    (pad "2" smd roundrect (at 0.485 0 90) (size 0.59 0.64) (layers "F.Cu" "F.Paste" "F.Mask") (roundrect_rratio 0.25)
      (net 667 "Net-(U17-PF27)") (pintype "passive"))
  )
	(footprint "kria-k26-devboard-footprints:R_0402_1005Metric" (layer "F.Cu")
    (at 84.046 94.249 180)
    (descr "Resistor SMD 0402")
    (tags "resistor SMD 0402")
    (property "Author" "Antmicro")
    (property "License" "Apache-2.0")
    (property "MPN" "CR0402-FX-2201GLF")
    (property "Manufacturer" "Bourns")
    (property "Sheetfile" "camera.kicad_sch")
    (property "Sheetname" "Camera interface")
    (property "Tolerance" "1%")
    (property "Val" "2k2")
    (property "ki_description" "2k2 resistor in 0402 package with 1% tolerance")
    (attr smd)
    (fp_text reference "R32" (at 1.07 3.64 180) (layer "F.SilkS")
        (effects (font (size 0.7 0.7) (thickness 0.15)) (justify left bottom))
    )
    (fp_text value "R_2k2_0402" (at 0 1.4 180) (layer "F.Fab") hide
        (effects (font (size 0.7 0.7) (thickness 0.15)) (justify left bottom))
    )
    (fp_text user "${REFERENCE}" (at -0.95 3.168 180) (layer "F.Fab") hide
        (effects (font (size 0.7 0.7) (thickness 0.15)) (justify left bottom))
    )
    (fp_text user "Author: Antmicro" (at -0.95 4.169 180) (layer "F.Fab") hide
        (effects (font (size 0.7 0.7) (thickness 0.15)) (justify left bottom))
    )
    (fp_text user "License: Apache-2.0" (at -0.95 5.169 180) (layer "F.Fab") hide
        (effects (font (size 0.7 0.7) (thickness 0.15)) (justify left bottom))
    )
    (fp_rect (start -0.93 -0.47) (end 0.93 0.47)
      (stroke (width 0.05) (type solid)) (fill none) (layer "F.CrtYd"))
    (fp_rect (start -0.5 -0.25) (end 0.5 0.25)
      (stroke (width 0.15) (type solid)) (fill none) (layer "F.Fab"))
    (pad "1" smd roundrect (at -0.485 0 180) (size 0.59 0.64) (layers "F.Cu" "F.Paste" "F.Mask") (roundrect_rratio 0.25)
      (net 20 "PL_3V3") (pintype "passive"))
    (pad "2" smd roundrect (at 0.485 0 180) (size 0.59 0.64) (layers "F.Cu" "F.Paste" "F.Mask") (roundrect_rratio 0.25)
      (net 194 "/Camera interface/CCI1_I2C_SDA_3V3") (pintype "passive"))
  )
	(footprint "kria-k26-devboard-footprints:R_0402_1005Metric" (layer "F.Cu")
    (at 84.05 96.25 180)
    (descr "Resistor SMD 0402")
    (tags "resistor SMD 0402")
    (property "Author" "Antmicro")
    (property "License" "Apache-2.0")
    (property "MPN" "CR0402-FX-2201GLF")
    (property "Manufacturer" "Bourns")
    (property "Sheetfile" "camera.kicad_sch")
    (property "Sheetname" "Camera interface")
    (property "Tolerance" "1%")
    (property "Val" "2k2")
    (property "ki_description" "2k2 resistor in 0402 package with 1% tolerance")
    (attr smd)
    (fp_text reference "R31" (at 1.07 3.64 180) (layer "F.SilkS")
        (effects (font (size 0.7 0.7) (thickness 0.15)) (justify left bottom))
    )
    (fp_text value "R_2k2_0402" (at 0 1.4 180) (layer "F.Fab") hide
        (effects (font (size 0.7 0.7) (thickness 0.15)) (justify left bottom))
    )
    (fp_text user "License: Apache-2.0" (at -0.95 5.169 180) (layer "F.Fab") hide
        (effects (font (size 0.7 0.7) (thickness 0.15)) (justify left bottom))
    )
    (fp_text user "${REFERENCE}" (at -0.95 3.168 180) (layer "F.Fab") hide
        (effects (font (size 0.7 0.7) (thickness 0.15)) (justify left bottom))
    )
    (fp_text user "Author: Antmicro" (at -0.95 4.169 180) (layer "F.Fab") hide
        (effects (font (size 0.7 0.7) (thickness 0.15)) (justify left bottom))
    )
    (fp_rect (start -0.93 -0.47) (end 0.93 0.47)
      (stroke (width 0.05) (type solid)) (fill none) (layer "F.CrtYd"))
    (fp_rect (start -0.5 -0.25) (end 0.5 0.25)
      (stroke (width 0.15) (type solid)) (fill none) (layer "F.Fab"))
    (pad "1" smd roundrect (at -0.485 0 180) (size 0.59 0.64) (layers "F.Cu" "F.Paste" "F.Mask") (roundrect_rratio 0.25)
      (net 20 "PL_3V3") (pintype "passive"))
    (pad "2" smd roundrect (at 0.485 0 180) (size 0.59 0.64) (layers "F.Cu" "F.Paste" "F.Mask") (roundrect_rratio 0.25)
      (net 196 "/Camera interface/CCI0_I2C_SDA_3V3") (pintype "passive"))
  )
	(footprint "kria-k26-devboard-footprints:R_0402_1005Metric" (layer "F.Cu")
    (at 84.05 93.25 180)
    (descr "Resistor SMD 0402")
    (tags "resistor SMD 0402")
    (property "Author" "Antmicro")
    (property "License" "Apache-2.0")
    (property "MPN" "CR0402-FX-2201GLF")
    (property "Manufacturer" "Bourns")
    (property "Sheetfile" "camera.kicad_sch")
    (property "Sheetname" "Camera interface")
    (property "Tolerance" "1%")
    (property "Val" "2k2")
    (property "ki_description" "2k2 resistor in 0402 package with 1% tolerance")
    (attr smd)
    (fp_text reference "R30" (at 1.07 3.64 180) (layer "F.SilkS")
        (effects (font (size 0.7 0.7) (thickness 0.15)) (justify left bottom))
    )
    (fp_text value "R_2k2_0402" (at 0 1.4 180) (layer "F.Fab") hide
        (effects (font (size 0.7 0.7) (thickness 0.15)) (justify left bottom))
    )
    (fp_text user "License: Apache-2.0" (at -0.95 5.169 180) (layer "F.Fab") hide
        (effects (font (size 0.7 0.7) (thickness 0.15)) (justify left bottom))
    )
    (fp_text user "Author: Antmicro" (at -0.95 4.169 180) (layer "F.Fab") hide
        (effects (font (size 0.7 0.7) (thickness 0.15)) (justify left bottom))
    )
    (fp_text user "${REFERENCE}" (at -0.95 3.168 180) (layer "F.Fab") hide
        (effects (font (size 0.7 0.7) (thickness 0.15)) (justify left bottom))
    )
    (fp_rect (start -0.93 -0.47) (end 0.93 0.47)
      (stroke (width 0.05) (type solid)) (fill none) (layer "F.CrtYd"))
    (fp_rect (start -0.5 -0.25) (end 0.5 0.25)
      (stroke (width 0.15) (type solid)) (fill none) (layer "F.Fab"))
    (pad "1" smd roundrect (at -0.485 0 180) (size 0.59 0.64) (layers "F.Cu" "F.Paste" "F.Mask") (roundrect_rratio 0.25)
      (net 20 "PL_3V3") (pintype "passive"))
    (pad "2" smd roundrect (at 0.485 0 180) (size 0.59 0.64) (layers "F.Cu" "F.Paste" "F.Mask") (roundrect_rratio 0.25)
      (net 193 "/Camera interface/CCI1_I2C_SCL_3V3") (pintype "passive"))
  )
	(footprint "kria-k26-devboard-footprints:R_0402_1005Metric" (layer "F.Cu")
    (at 84.046 95.25 180)
    (descr "Resistor SMD 0402")
    (tags "resistor SMD 0402")
    (property "Author" "Antmicro")
    (property "License" "Apache-2.0")
    (property "MPN" "CR0402-FX-2201GLF")
    (property "Manufacturer" "Bourns")
    (property "Sheetfile" "camera.kicad_sch")
    (property "Sheetname" "Camera interface")
    (property "Tolerance" "1%")
    (property "Val" "2k2")
    (property "ki_description" "2k2 resistor in 0402 package with 1% tolerance")
    (attr smd)
    (fp_text reference "R29" (at 1.07 3.64 180) (layer "F.SilkS")
        (effects (font (size 0.7 0.7) (thickness 0.15)) (justify left bottom))
    )
    (fp_text value "R_2k2_0402" (at 0 1.4 180) (layer "F.Fab") hide
        (effects (font (size 0.7 0.7) (thickness 0.15)) (justify left bottom))
    )
    (fp_text user "License: Apache-2.0" (at -0.95 5.169 180) (layer "F.Fab") hide
        (effects (font (size 0.7 0.7) (thickness 0.15)) (justify left bottom))
    )
    (fp_text user "${REFERENCE}" (at -0.95 3.168 180) (layer "F.Fab") hide
        (effects (font (size 0.7 0.7) (thickness 0.15)) (justify left bottom))
    )
    (fp_text user "Author: Antmicro" (at -0.95 4.169 180) (layer "F.Fab") hide
        (effects (font (size 0.7 0.7) (thickness 0.15)) (justify left bottom))
    )
    (fp_rect (start -0.93 -0.47) (end 0.93 0.47)
      (stroke (width 0.05) (type solid)) (fill none) (layer "F.CrtYd"))
    (fp_rect (start -0.5 -0.25) (end 0.5 0.25)
      (stroke (width 0.15) (type solid)) (fill none) (layer "F.Fab"))
    (pad "1" smd roundrect (at -0.485 0 180) (size 0.59 0.64) (layers "F.Cu" "F.Paste" "F.Mask") (roundrect_rratio 0.25)
      (net 20 "PL_3V3") (pintype "passive"))
    (pad "2" smd roundrect (at 0.485 0 180) (size 0.59 0.64) (layers "F.Cu" "F.Paste" "F.Mask") (roundrect_rratio 0.25)
      (net 195 "/Camera interface/CCI0_I2C_SCL_3V3") (pintype "passive"))
  )
	(footprint "kria-k26-devboard-footprints:TP_SMD_0.75mm" (layer "F.Cu")
    (at 81.6 95.2008)
    (property "Author" "Antmicro")
    (property "License" "Apache-2.0")
    (property "MPN" "")
    (property "Manufacturer" "")
    (property "Sheetfile" "camera.kicad_sch")
    (property "Sheetname" "Camera interface")
    (property "ki_description" "Test Point 0.75mm")
    (attr exclude_from_pos_files)
    (fp_text reference "TP4" (at -2.38 0.35) (layer "F.SilkS")
        (effects (font (size 0.7 0.7) (thickness 0.15)) (justify left bottom))
    )
    (fp_text value "TP_0.75mm_SMD" (at 0 1.2) (layer "F.Fab") hide
        (effects (font (size 0.7 0.7) (thickness 0.15)) (justify left bottom))
    )
    (fp_text user "${REFERENCE}" (at -0.4 2.7) (layer "F.Fab") hide
        (effects (font (size 0.7 0.7) (thickness 0.15)) (justify left bottom))
    )
    (fp_text user "License: Apache-2.0" (at -0.4 5.101) (layer "F.Fab") hide
        (effects (font (size 0.7 0.7) (thickness 0.15)) (justify left bottom))
    )
    (fp_text user "Author: Antmicro" (at -0.4 3.901) (layer "F.Fab") hide
        (effects (font (size 0.7 0.7) (thickness 0.15)) (justify left bottom))
    )
    (pad "1" smd circle (at 0 0) (size 0.75 0.75) (layers "F.Cu" "F.Mask")
      (net 195 "/Camera interface/CCI0_I2C_SCL_3V3") (pinfunction "1") (pintype "passive"))
  )
	(footprint "kria-k26-devboard-footprints:TP_SMD_0.75mm" (layer "F.Cu")
    (at 81.6 96.2)
    (property "Author" "Antmicro")
    (property "License" "Apache-2.0")
    (property "MPN" "")
    (property "Manufacturer" "")
    (property "Sheetfile" "camera.kicad_sch")
    (property "Sheetname" "Camera interface")
    (property "ki_description" "Test Point 0.75mm")
    (attr exclude_from_pos_files)
    (fp_text reference "TP5" (at -2.38 0.35) (layer "F.SilkS")
        (effects (font (size 0.7 0.7) (thickness 0.15)) (justify left bottom))
    )
    (fp_text value "TP_0.75mm_SMD" (at 0 1.2) (layer "F.Fab") hide
        (effects (font (size 0.7 0.7) (thickness 0.15)) (justify left bottom))
    )
    (fp_text user "Author: Antmicro" (at -0.4 3.901) (layer "F.Fab") hide
        (effects (font (size 0.7 0.7) (thickness 0.15)) (justify left bottom))
    )
    (fp_text user "License: Apache-2.0" (at -0.4 5.101) (layer "F.Fab") hide
        (effects (font (size 0.7 0.7) (thickness 0.15)) (justify left bottom))
    )
    (fp_text user "${REFERENCE}" (at -0.4 2.7) (layer "F.Fab") hide
        (effects (font (size 0.7 0.7) (thickness 0.15)) (justify left bottom))
    )
    (pad "1" smd circle (at 0 0) (size 0.75 0.75) (layers "F.Cu" "F.Mask")
      (net 196 "/Camera interface/CCI0_I2C_SDA_3V3") (pinfunction "1") (pintype "passive"))
  )
	(footprint "kria-k26-devboard-footprints:TP_SMD_0.75mm" (layer "F.Cu")
    (at 81.6 93.1)
    (property "Author" "Antmicro")
    (property "License" "Apache-2.0")
    (property "MPN" "")
    (property "Manufacturer" "")
    (property "Sheetfile" "camera.kicad_sch")
    (property "Sheetname" "Camera interface")
    (property "ki_description" "Test Point 0.75mm")
    (attr exclude_from_pos_files)
    (fp_text reference "TP6" (at -2.38 0.35) (layer "F.SilkS")
        (effects (font (size 0.7 0.7) (thickness 0.15)) (justify left bottom))
    )
    (fp_text value "TP_0.75mm_SMD" (at 0 1.2) (layer "F.Fab") hide
        (effects (font (size 0.7 0.7) (thickness 0.15)) (justify left bottom))
    )
    (fp_text user "Author: Antmicro" (at -0.4 3.901) (layer "F.Fab") hide
        (effects (font (size 0.7 0.7) (thickness 0.15)) (justify left bottom))
    )
    (fp_text user "${REFERENCE}" (at -0.4 2.7) (layer "F.Fab") hide
        (effects (font (size 0.7 0.7) (thickness 0.15)) (justify left bottom))
    )
    (fp_text user "License: Apache-2.0" (at -0.4 5.101) (layer "F.Fab") hide
        (effects (font (size 0.7 0.7) (thickness 0.15)) (justify left bottom))
    )
    (pad "1" smd circle (at 0 0) (size 0.75 0.75) (layers "F.Cu" "F.Mask")
      (net 193 "/Camera interface/CCI1_I2C_SCL_3V3") (pinfunction "1") (pintype "passive"))
  )
	(footprint "kria-k26-devboard-footprints:TP_SMD_0.75mm" (layer "F.Cu")
    (at 81.6 94.1)
    (property "Author" "Antmicro")
    (property "License" "Apache-2.0")
    (property "MPN" "")
    (property "Manufacturer" "")
    (property "Sheetfile" "camera.kicad_sch")
    (property "Sheetname" "Camera interface")
    (property "ki_description" "Test Point 0.75mm")
    (attr exclude_from_pos_files)
    (fp_text reference "TP7" (at -2.38 0.35) (layer "F.SilkS")
        (effects (font (size 0.7 0.7) (thickness 0.15)) (justify left bottom))
    )
    (fp_text value "TP_0.75mm_SMD" (at 0 1.2) (layer "F.Fab") hide
        (effects (font (size 0.7 0.7) (thickness 0.15)) (justify left bottom))
    )
    (fp_text user "${REFERENCE}" (at -0.4 2.7) (layer "F.Fab") hide
        (effects (font (size 0.7 0.7) (thickness 0.15)) (justify left bottom))
    )
    (fp_text user "Author: Antmicro" (at -0.4 3.901) (layer "F.Fab") hide
        (effects (font (size 0.7 0.7) (thickness 0.15)) (justify left bottom))
    )
    (fp_text user "License: Apache-2.0" (at -0.4 5.101) (layer "F.Fab") hide
        (effects (font (size 0.7 0.7) (thickness 0.15)) (justify left bottom))
    )
    (pad "1" smd circle (at 0 0) (size 0.75 0.75) (layers "F.Cu" "F.Mask")
      (net 194 "/Camera interface/CCI1_I2C_SDA_3V3") (pinfunction "1") (pintype "passive"))
  )
)
